# T6G (Grand Teton) — schematic netlist excerpt (pin names and nets, part order shuffled) for the footprints in the layout excerpt that follows; sources: Cadence DE-HDL packaged netlist, KiCad conversion of 04192023_DAF0TMB3IC0_F0TG_MB_C_brd_V02_OCP.brd

R3457  Q_RES  10K 1% CHIP  pkg 0402LF  page 128 : A = GPU_BASE_STBY_EN_BUF_R ; B = GND
PR354  Q_RES  5.6 1% CHIP  pkg 0402LF  page 196 : A = SW_PVDDCR_CPU0_P0_BOOT5 ; B = SW_PVDDCR_CPU0_P0_BOOT5_RC

(kicad_pcb
	(version 20260206)
	(generator "pcbnew")
	(generator_version "10.0")
	(general
		(thickness 1.6)
		(legacy_teardrops no)
	)
	(paper "A4")
	(title_block
		(title "04192023_DAF0TMB3IC0_F0TG_MB_C_brd_V02_OCP.brd")
		(comment 1 "Grand Teton / footprints 4356-4357 of 8354")
	)
	(layers
		(0 "F.Cu" signal "TOP")
		(4 "In1.Cu" signal "GND")
		(6 "In2.Cu" signal "IN1")
		(8 "In3.Cu" signal "GND1")
		(10 "In4.Cu" signal "IN2")
		(12 "In5.Cu" signal "GND2")
		(14 "In6.Cu" signal "IN3")
		(16 "In7.Cu" signal "GND3")
		(18 "In8.Cu" signal "VCC")
		(20 "In9.Cu" signal "VCC1")
		(22 "In10.Cu" signal "GND4")
		(24 "In11.Cu" signal "IN4")
		(26 "In12.Cu" signal "GND5")
		(28 "In13.Cu" signal "IN5")
		(30 "In14.Cu" signal "GND6")
		(32 "In15.Cu" signal "IN6")
		(34 "In16.Cu" signal "GND7")
		(2 "B.Cu" signal "BOTTOM")
		(9 "F.Adhes" user "F.Adhesive")
		(11 "B.Adhes" user "B.Adhesive")
		(13 "F.Paste" user "Package Geometry/Pastemask Top")
		(15 "B.Paste" user "Package Geometry/Pastemask Bottom")
		(5 "F.SilkS" user "Ref Des/Silkscreen Top")
		(7 "B.SilkS" user "Ref Des/Silkscreen Bottom")
		(1 "F.Mask" user "Board Geometry/Soldermask Top")
		(3 "B.Mask" user "Board Geometry/Soldermask Bottom")
		(17 "Dwgs.User" user "User.Drawings")
		(19 "Cmts.User" user "User.Comments")
		(21 "Eco1.User" user "User.Eco1")
		(23 "Eco2.User" user "User.Eco2")
		(25 "Edge.Cuts" user "Board Geometry/Outline")
		(27 "Margin" user)
		(31 "F.CrtYd" user "Package Geometry/Place Bound Top")
		(29 "B.CrtYd" user "Package Geometry/Place Bound Bottom")
		(35 "F.Fab" user "Ref Des/Assembly Top")
		(33 "B.Fab" user "Ref Des/Assembly Bottom")
	)
	(footprint ""
		(layer "F.Cu")
		(at 355.274372 -164.844222 -90)
		(property "Reference" "PR354"
			(at 0 0 270)
			(layer "F.SilkS")
			(hide yes)
			(effects
				(font
					(size 1.27 1.27)
				)
			)
		)
		(property "Value" ""
			(at 0 0 270)
			(layer "F.Fab")
			(effects
				(font
					(size 1.27 1.27)
				)
			)
		)
		(duplicate_pad_numbers_are_jumpers no)
		(fp_line
			(start -0.7874 0.4064)
			(end -0.7874 -0.4064)
			(stroke
				(width 0.1524)
				(type default)
			)
			(layer "F.SilkS")
		)
		(fp_line
			(start 0.7874 0.4064)
			(end -0.7874 0.4064)
			(stroke
				(width 0.1524)
				(type default)
			)
			(layer "F.SilkS")
		)
		(fp_line
			(start -0.7874 -0.4064)
			(end 0.7874 -0.4064)
			(stroke
				(width 0.1524)
				(type default)
			)
			(layer "F.SilkS")
		)
		(fp_line
			(start 0.7874 -0.4064)
			(end 0.7874 0.4064)
			(stroke
				(width 0.1524)
				(type default)
			)
			(layer "F.SilkS")
		)
		(fp_line
			(start -0.67945 0.3048)
			(end -0.67945 -0.305054)
			(stroke
				(width 0.1)
				(type default)
			)
			(layer "F.Fab")
		)
		(fp_line
			(start -0.12065 0.3048)
			(end -0.67945 0.3048)
			(stroke
				(width 0.1)
				(type default)
			)
			(layer "F.Fab")
		)
		(fp_line
			(start 0.120396 0.3048)
			(end 0.120396 0.2794)
			(stroke
				(width 0.1)
				(type default)
			)
			(layer "F.Fab")
		)
		(fp_line
			(start 0.67945 0.3048)
			(end 0.120396 0.3048)
			(stroke
				(width 0.1)
				(type default)
			)
			(layer "F.Fab")
		)
		(fp_line
			(start -0.12065 0.2794)
			(end -0.12065 0.3048)
			(stroke
				(width 0.1)
				(type default)
			)
			(layer "F.Fab")
		)
		(fp_line
			(start 0.120396 0.2794)
			(end -0.12065 0.2794)
			(stroke
				(width 0.1)
				(type default)
			)
			(layer "F.Fab")
		)
		(fp_line
			(start -0.12065 -0.2794)
			(end 0.12065 -0.2794)
			(stroke
				(width 0.1)
				(type default)
			)
			(layer "F.Fab")
		)
		(fp_line
			(start 0.12065 -0.2794)
			(end 0.12065 -0.3048)
			(stroke
				(width 0.1)
				(type default)
			)
			(layer "F.Fab")
		)
		(fp_line
			(start 0.12065 -0.3048)
			(end 0.67945 -0.3048)
			(stroke
				(width 0.1)
				(type default)
			)
			(layer "F.Fab")
		)
		(fp_line
			(start 0.67945 -0.3048)
			(end 0.67945 0.3048)
			(stroke
				(width 0.1)
				(type default)
			)
			(layer "F.Fab")
		)
		(fp_line
			(start -0.67945 -0.305054)
			(end -0.12065 -0.305054)
			(stroke
				(width 0.1)
				(type default)
			)
			(layer "F.Fab")
		)
		(fp_line
			(start -0.12065 -0.305054)
			(end -0.12065 -0.2794)
			(stroke
				(width 0.1)
				(type default)
			)
			(layer "F.Fab")
		)
		(pad "1" smd circle
			(at -0.40005 0 270)
			(size 0 0)
			(layers "F.Cu" "F.Mask" "F.Paste")
			(net "SW_PVDDCR_CPU0_P0_BOOT5")
		)
		(pad "2" smd circle
			(at 0.40005 0 270)
			(size 0 0)
			(layers "F.Cu" "F.Mask" "F.Paste")
			(net "SW_PVDDCR_CPU0_P0_BOOT5_RC")
		)
	)
	(footprint ""
		(layer "F.Cu")
		(at 118.491 -425.704)
		(property "Reference" "R3457"
			(at 0 0 0)
			(layer "F.SilkS")
			(hide yes)
			(effects
				(font
					(size 1.27 1.27)
				)
			)
		)
		(property "Value" ""
			(at 0 0 0)
			(layer "F.Fab")
			(effects
				(font
					(size 1.27 1.27)
				)
			)
		)
		(duplicate_pad_numbers_are_jumpers no)
		(fp_line
			(start -0.7874 -0.4064)
			(end 0.7874 -0.4064)
			(stroke
				(width 0.1524)
				(type default)
			)
			(layer "F.SilkS")
		)
		(fp_line
			(start -0.7874 0.4064)
			(end -0.7874 -0.4064)
			(stroke
				(width 0.1524)
				(type default)
			)
			(layer "F.SilkS")
		)
		(fp_line
			(start 0.7874 -0.4064)
			(end 0.7874 0.4064)
			(stroke
				(width 0.1524)
				(type default)
			)
			(layer "F.SilkS")
		)
		(fp_line
			(start 0.7874 0.4064)
			(end -0.7874 0.4064)
			(stroke
				(width 0.1524)
				(type default)
			)
			(layer "F.SilkS")
		)
		(fp_line
			(start -0.67945 -0.305054)
			(end -0.12065 -0.305054)
			(stroke
				(width 0.1)
				(type default)
			)
			(layer "F.Fab")
		)
		(fp_line
			(start -0.67945 0.3048)
			(end -0.67945 -0.305054)
			(stroke
				(width 0.1)
				(type default)
			)
			(layer "F.Fab")
		)
		(fp_line
			(start -0.12065 -0.305054)
			(end -0.12065 -0.2794)
			(stroke
				(width 0.1)
				(type default)
			)
			(layer "F.Fab")
		)
		(fp_line
			(start -0.12065 -0.2794)
			(end 0.12065 -0.2794)
			(stroke
				(width 0.1)
				(type default)
			)
			(layer "F.Fab")
		)
		(fp_line
			(start -0.12065 0.2794)
			(end -0.12065 0.3048)
			(stroke
				(width 0.1)
				(type default)
			)
			(layer "F.Fab")
		)
		(fp_line
			(start -0.12065 0.3048)
			(end -0.67945 0.3048)
			(stroke
				(width 0.1)
				(type default)
			)
			(layer "F.Fab")
		)
		(fp_line
			(start 0.120396 0.2794)
			(end -0.12065 0.2794)
			(stroke
				(width 0.1)
				(type default)
			)
			(layer "F.Fab")
		)
		(fp_line
			(start 0.120396 0.3048)
			(end 0.120396 0.2794)
			(stroke
				(width 0.1)
				(type default)
			)
			(layer "F.Fab")
		)
		(fp_line
			(start 0.12065 -0.3048)
			(end 0.67945 -0.3048)
			(stroke
				(width 0.1)
				(type default)
			)
			(layer "F.Fab")
		)
		(fp_line
			(start 0.12065 -0.2794)
			(end 0.12065 -0.3048)
			(stroke
				(width 0.1)
				(type default)
			)
			(layer "F.Fab")
		)
		(fp_line
			(start 0.67945 -0.3048)
			(end 0.67945 0.3048)
			(stroke
				(width 0.1)
				(type default)
			)
			(layer "F.Fab")
		)
		(fp_line
			(start 0.67945 0.3048)
			(end 0.120396 0.3048)
			(stroke
				(width 0.1)
				(type default)
			)
			(layer "F.Fab")
		)
		(pad "1" smd circle
			(at -0.40005 0)
			(size 0 0)
			(layers "F.Cu" "F.Mask" "F.Paste")
			(net "GPU_BASE_STBY_EN_BUF_R")
		)
		(pad "2" smd circle
			(at 0.40005 0)
			(size 0 0)
			(layers "F.Cu" "F.Mask" "F.Paste")
			(net "GND")
		)
	)
)
